(kicad_pcb
	(version 20260206)
	(generator "pcbnew")
	(generator_version "10.0")
	(general
		(thickness 1.6)
		(legacy_teardrops no)
	)
	(paper "A4")
	(title_block
		(title "01162023_DA0F0TEBIF0_F0T_Expander_BD_F_brd_V02_OCP.brd")
		(comment 1 "Grand Teton / footprints 4757-4759 of 9728")
	)
	(layers
		(0 "F.Cu" signal "TOP")
		(4 "In1.Cu" signal "GND")
		(6 "In2.Cu" signal "VCC")
		(8 "In3.Cu" signal "VCC1")
		(10 "In4.Cu" signal "GND1")
		(12 "In5.Cu" signal "IN1")
		(14 "In6.Cu" signal "GND2")
		(16 "In7.Cu" signal "IN2")
		(18 "In8.Cu" signal "GND3")
		(20 "In9.Cu" signal "IN3")
		(22 "In10.Cu" signal "GND4")
		(24 "In11.Cu" signal "IN4")
		(26 "In12.Cu" signal "GND5")
		(28 "In13.Cu" signal "IN5")
		(30 "In14.Cu" signal "GND6")
		(32 "In15.Cu" signal "IN6")
		(34 "In16.Cu" signal "GND7")
		(2 "B.Cu" signal "BOTTOM")
		(9 "F.Adhes" user "F.Adhesive")
		(11 "B.Adhes" user "B.Adhesive")
		(13 "F.Paste" user "Package Geometry/Pastemask Top")
		(15 "B.Paste" user "Package Geometry/Pastemask Bottom")
		(5 "F.SilkS" user "Ref Des/Silkscreen Top")
		(7 "B.SilkS" user "Ref Des/Silkscreen Bottom")
		(1 "F.Mask" user "Board Geometry/Soldermask Top")
		(3 "B.Mask" user "Board Geometry/Soldermask Bottom")
		(17 "Dwgs.User" user "User.Drawings")
		(19 "Cmts.User" user "User.Comments")
		(21 "Eco1.User" user "User.Eco1")
		(23 "Eco2.User" user "User.Eco2")
		(25 "Edge.Cuts" user "Board Geometry/Outline")
		(27 "Margin" user)
		(31 "F.CrtYd" user "Package Geometry/Place Bound Top")
		(29 "B.CrtYd" user "Package Geometry/Place Bound Bottom")
		(35 "F.Fab" user "Ref Des/Assembly Top")
		(33 "B.Fab" user "Ref Des/Assembly Bottom")
	)
	(footprint ""
		(layer "F.Cu")
		(at 217.235786 -221.350586 180)
		(property "Reference" "R1493"
			(at 0 0 180)
			(layer "F.SilkS")
			(hide yes)
			(effects
				(font
					(size 1.27 1.27)
				)
			)
		)
		(property "Value" ""
			(at 0 0 180)
			(layer "F.Fab")
			(effects
				(font
					(size 1.27 1.27)
				)
			)
		)
		(duplicate_pad_numbers_are_jumpers no)
		(fp_line
			(start 0.7874 0.4064)
			(end -0.7874 0.4064)
			(stroke
				(width 0.1524)
				(type default)
			)
			(layer "F.SilkS")
		)
		(fp_line
			(start 0.7874 -0.4064)
			(end 0.7874 0.4064)
			(stroke
				(width 0.1524)
				(type default)
			)
			(layer "F.SilkS")
		)
		(fp_line
			(start -0.7874 0.4064)
			(end -0.7874 -0.4064)
			(stroke
				(width 0.1524)
				(type default)
			)
			(layer "F.SilkS")
		)
		(fp_line
			(start -0.7874 -0.4064)
			(end 0.7874 -0.4064)
			(stroke
				(width 0.1524)
				(type default)
			)
			(layer "F.SilkS")
		)
		(fp_line
			(start 0.67945 0.3048)
			(end 0.120396 0.3048)
			(stroke
				(width 0.1)
				(type default)
			)
			(layer "F.Fab")
		)
		(fp_line
			(start 0.67945 -0.3048)
			(end 0.67945 0.3048)
			(stroke
				(width 0.1)
				(type default)
			)
			(layer "F.Fab")
		)
		(fp_line
			(start 0.12065 -0.2794)
			(end 0.12065 -0.3048)
			(stroke
				(width 0.1)
				(type default)
			)
			(layer "F.Fab")
		)
		(fp_line
			(start 0.12065 -0.3048)
			(end 0.67945 -0.3048)
			(stroke
				(width 0.1)
				(type default)
			)
			(layer "F.Fab")
		)
		(fp_line
			(start 0.120396 0.3048)
			(end 0.120396 0.2794)
			(stroke
				(width 0.1)
				(type default)
			)
			(layer "F.Fab")
		)
		(fp_line
			(start 0.120396 0.2794)
			(end -0.12065 0.2794)
			(stroke
				(width 0.1)
				(type default)
			)
			(layer "F.Fab")
		)
		(fp_line
			(start -0.12065 0.3048)
			(end -0.67945 0.3048)
			(stroke
				(width 0.1)
				(type default)
			)
			(layer "F.Fab")
		)
		(fp_line
			(start -0.12065 0.2794)
			(end -0.12065 0.3048)
			(stroke
				(width 0.1)
				(type default)
			)
			(layer "F.Fab")
		)
		(fp_line
			(start -0.12065 -0.2794)
			(end 0.12065 -0.2794)
			(stroke
				(width 0.1)
				(type default)
			)
			(layer "F.Fab")
		)
		(fp_line
			(start -0.12065 -0.305054)
			(end -0.12065 -0.2794)
			(stroke
				(width 0.1)
				(type default)
			)
			(layer "F.Fab")
		)
		(fp_line
			(start -0.67945 0.3048)
			(end -0.67945 -0.305054)
			(stroke
				(width 0.1)
				(type default)
			)
			(layer "F.Fab")
		)
		(fp_line
			(start -0.67945 -0.305054)
			(end -0.12065 -0.305054)
			(stroke
				(width 0.1)
				(type default)
			)
			(layer "F.Fab")
		)
		(pad "1" smd circle
			(at -0.40005 0 180)
			(size 0 0)
			(layers "F.Cu" "F.Mask" "F.Paste")
			(net "SMB_BIC_I2C9_SSD_MUX_SDA")
		)
		(pad "2" smd circle
			(at 0.40005 0 180)
			(size 0 0)
			(layers "F.Cu" "F.Mask" "F.Paste")
			(net "SMB_BIC_I2C9_SSD_MUX_R_SDA")
		)
	)
	(footprint ""
		(layer "F.Cu")
		(at 115.600226 -120.093486 180)
		(property "Reference" "PC594"
			(at 0 0 180)
			(layer "F.SilkS")
			(hide yes)
			(effects
				(font
					(size 1.27 1.27)
				)
			)
		)
		(property "Value" ""
			(at 0 0 180)
			(layer "F.Fab")
			(effects
				(font
					(size 1.27 1.27)
				)
			)
		)
		(duplicate_pad_numbers_are_jumpers no)
		(fp_line
			(start 0.7874 0.4064)
			(end -0.7874 0.4064)
			(stroke
				(width 0.1524)
				(type default)
			)
			(layer "F.SilkS")
		)
		(fp_line
			(start 0.7874 -0.4064)
			(end 0.7874 0.4064)
			(stroke
				(width 0.1524)
				(type default)
			)
			(layer "F.SilkS")
		)
		(fp_line
			(start -0.7874 0.4064)
			(end -0.7874 -0.4064)
			(stroke
				(width 0.1524)
				(type default)
			)
			(layer "F.SilkS")
		)
		(fp_line
			(start -0.7874 -0.4064)
			(end 0.7874 -0.4064)
			(stroke
				(width 0.1524)
				(type default)
			)
			(layer "F.SilkS")
		)
		(fp_line
			(start 0.67945 0.3048)
			(end 0.120396 0.3048)
			(stroke
				(width 0.1)
				(type default)
			)
			(layer "F.Fab")
		)
		(fp_line
			(start 0.67945 -0.3048)
			(end 0.67945 0.3048)
			(stroke
				(width 0.1)
				(type default)
			)
			(layer "F.Fab")
		)
		(fp_line
			(start 0.12065 -0.2794)
			(end 0.12065 -0.3048)
			(stroke
				(width 0.1)
				(type default)
			)
			(layer "F.Fab")
		)
		(fp_line
			(start 0.12065 -0.3048)
			(end 0.67945 -0.3048)
			(stroke
				(width 0.1)
				(type default)
			)
			(layer "F.Fab")
		)
		(fp_line
			(start 0.120396 0.3048)
			(end 0.120396 0.2794)
			(stroke
				(width 0.1)
				(type default)
			)
			(layer "F.Fab")
		)
		(fp_line
			(start 0.120396 0.2794)
			(end -0.12065 0.2794)
			(stroke
				(width 0.1)
				(type default)
			)
			(layer "F.Fab")
		)
		(fp_line
			(start -0.12065 0.3048)
			(end -0.67945 0.3048)
			(stroke
				(width 0.1)
				(type default)
			)
			(layer "F.Fab")
		)
		(fp_line
			(start -0.12065 0.2794)
			(end -0.12065 0.3048)
			(stroke
				(width 0.1)
				(type default)
			)
			(layer "F.Fab")
		)
		(fp_line
			(start -0.12065 -0.2794)
			(end 0.12065 -0.2794)
			(stroke
				(width 0.1)
				(type default)
			)
			(layer "F.Fab")
		)
		(fp_line
			(start -0.12065 -0.305054)
			(end -0.12065 -0.2794)
			(stroke
				(width 0.1)
				(type default)
			)
			(layer "F.Fab")
		)
		(fp_line
			(start -0.67945 0.3048)
			(end -0.67945 -0.305054)
			(stroke
				(width 0.1)
				(type default)
			)
			(layer "F.Fab")
		)
		(fp_line
			(start -0.67945 -0.305054)
			(end -0.12065 -0.305054)
			(stroke
				(width 0.1)
				(type default)
			)
			(layer "F.Fab")
		)
		(pad "1" smd circle
			(at -0.40005 0 180)
			(size 0 0)
			(layers "F.Cu" "F.Mask" "F.Paste")
			(net "P3V3_CO_GATE")
		)
		(pad "2" smd circle
			(at 0.40005 0 180)
			(size 0 0)
			(layers "F.Cu" "F.Mask" "F.Paste")
			(net "GND")
		)
	)
	(footprint ""
		(layer "F.Cu")
		(at 128.594612 -157.304994 -90)
		(property "Reference" "PU73"
			(at -3.221736 -1.554988 0)
			(unlocked yes)
			(layer "F.SilkS")
			(effects
				(font
					(size 0.7874 0.5842)
					(thickness 0.1524)
				)
				(justify left)
			)
		)
		(property "Value" ""
			(at 0 0 270)
			(layer "F.Fab")
			(effects
				(font
					(size 1.27 1.27)
				)
			)
		)
		(duplicate_pad_numbers_are_jumpers no)
		(fp_line
			(start -1.549908 2.549906)
			(end -0.753872 2.549906)
			(stroke
				(width 0.1524)
				(type default)
			)
			(layer "F.SilkS")
		)
		(fp_line
			(start -0.245872 2.549906)
			(end 0.245872 2.549906)
			(stroke
				(width 0.1524)
				(type default)
			)
			(layer "F.SilkS")
		)
		(fp_line
			(start 0.753872 2.549906)
			(end 1.549908 2.549906)
			(stroke
				(width 0.1524)
				(type default)
			)
			(layer "F.SilkS")
		)
		(fp_line
			(start 1.549908 2.549906)
			(end 1.549908 2.253996)
			(stroke
				(width 0.1524)
				(type default)
			)
			(layer "F.SilkS")
		)
		(fp_line
			(start -1.549908 2.253996)
			(end -1.549908 2.549906)
			(stroke
				(width 0.1524)
				(type default)
			)
			(layer "F.SilkS")
		)
		(fp_line
			(start 1.549908 -2.253996)
			(end 1.549908 -2.549906)
			(stroke
				(width 0.1524)
				(type default)
			)
			(layer "F.SilkS")
		)
		(fp_line
			(start -1.549908 -2.549906)
			(end -1.549908 -2.251964)
			(stroke
				(width 0.1524)
				(type default)
			)
			(layer "F.SilkS")
		)
		(fp_line
			(start -0.752094 -2.549906)
			(end -1.549908 -2.549906)
			(stroke
				(width 0.1524)
				(type default)
			)
			(layer "F.SilkS")
		)
		(fp_line
			(start 0.2413 -2.549906)
			(end -0.2413 -2.549906)
			(stroke
				(width 0.1524)
				(type default)
			)
			(layer "F.SilkS")
		)
		(fp_line
			(start 1.549908 -2.549906)
			(end 0.752094 -2.549906)
			(stroke
				(width 0.1524)
				(type default)
			)
			(layer "F.SilkS")
		)
		(fp_poly
			(pts
				(xy -1.688084 -2.346198) (xy -2.591308 -2.647442) (xy -1.989074 -3.249422)
			)
			(stroke
				(width 0)
				(type default)
			)
			(fill yes)
			(layer "F.SilkS")
		)
		(fp_line
			(start -1.549908 2.549906)
			(end 1.549908 2.549906)
			(stroke
				(width 0.1)
				(type default)
			)
			(layer "F.Fab")
		)
		(fp_line
			(start 1.549908 2.549906)
			(end 1.549908 -2.549906)
			(stroke
				(width 0.1)
				(type default)
			)
			(layer "F.Fab")
		)
		(fp_line
			(start -1.549908 -2.549906)
			(end -1.549908 2.549906)
			(stroke
				(width 0.1)
				(type default)
			)
			(layer "F.Fab")
		)
		(fp_line
			(start 1.549908 -2.549906)
			(end -1.549908 -2.549906)
			(stroke
				(width 0.1)
				(type default)
			)
			(layer "F.Fab")
		)
		(fp_poly
			(pts
				(xy -1.891538 -1.999996) (xy -2.7432 -1.574292) (xy -2.7432 -2.4257)
			)
			(stroke
				(width 0)
				(type default)
			)
			(fill yes)
			(layer "F.Fab")
		)
		(fp_text user "10"
			(at -1.411478 3.132328 270)
			(unlocked yes)
			(layer "F.SilkS")
			(effects
				(font
					(size 0.635 0.4064)
					(thickness 0.1524)
				)
			)
		)
		(fp_text user "11"
			(at 1.830578 2.879344 270)
			(unlocked yes)
			(layer "F.SilkS")
			(effects
				(font
					(size 0.635 0.4064)
					(thickness 0.1524)
				)
			)
		)
		(fp_text user "9"
			(at -2.338832 2.5908 180)
			(unlocked yes)
			(layer "F.SilkS")
			(effects
				(font
					(size 0.635 0.4064)
					(thickness 0.1524)
				)
			)
		)
		(fp_text user "12"
			(at 2.5019 1.055624 180)
			(unlocked yes)
			(layer "F.SilkS")
			(effects
				(font
					(size 0.635 0.4064)
					(thickness 0.1524)
				)
			)
		)
		(fp_text user "21_22"
			(at 0.41783 -3.434588 270)
			(unlocked yes)
			(layer "F.SilkS")
			(effects
				(font
					(size 0.635 0.4064)
					(thickness 0.1524)
				)
			)
		)
		(fp_text user "20"
			(at 2.17551 -3.919728 180)
			(unlocked yes)
			(layer "F.SilkS")
			(effects
				(font
					(size 0.635 0.4064)
					(thickness 0.1524)
				)
			)
		)
		(fp_text user "11"
			(at 1.1938 3.329432 270)
			(unlocked yes)
			(layer "F.Fab")
			(effects
				(font
					(size 0.635 0.4064)
					(thickness 0.1524)
				)
			)
		)
		(fp_text user "10"
			(at -1.4224 3.253232 270)
			(unlocked yes)
			(layer "F.Fab")
			(effects
				(font
					(size 0.635 0.4064)
					(thickness 0.1524)
				)
			)
		)
		(fp_text user "12"
			(at 2.207768 2.7178 180)
			(unlocked yes)
			(layer "F.Fab")
			(effects
				(font
					(size 0.635 0.4064)
					(thickness 0.1524)
				)
			)
		)
		(fp_text user "9"
			(at -2.338832 2.5908 180)
			(unlocked yes)
			(layer "F.Fab")
			(effects
				(font
					(size 0.635 0.4064)
					(thickness 0.1524)
				)
			)
		)
		(fp_text user "20"
			(at 2.055368 -2.7686 180)
			(unlocked yes)
			(layer "F.Fab")
			(effects
				(font
					(size 0.635 0.4064)
					(thickness 0.1524)
				)
			)
		)
		(fp_text user "21_22"
			(at -0.0762 -3.401568 270)
			(unlocked yes)
			(layer "F.Fab")
			(effects
				(font
					(size 0.635 0.4064)
					(thickness 0.1524)
				)
			)
		)
		(pad "1" smd circle
			(at -1.374902 -1.999996 180)
			(size 0 0)
			(layers "F.Cu" "F.Mask" "F.Paste")
			(net "P12V_NIC2_CO_EN")
		)
		(pad "2" smd rect
			(at -1.400048 -1.500124 180)
			(size 0.254 0.8128)
			(layers "F.Cu" "F.Mask" "F.Paste")
			(net "GND")
		)
		(pad "3" smd rect
			(at -1.400048 -0.999998 180)
			(size 0.254 0.8128)
			(layers "F.Cu" "F.Mask" "F.Paste")
			(net "GND")
		)
		(pad "4" smd rect
			(at -1.400048 -0.499872 180)
			(size 0.254 0.8128)
			(layers "F.Cu" "F.Mask" "F.Paste")
			(net "P12V_NIC2_CO_TIMER")
		)
		(pad "5" smd rect
			(at -1.400048 0 180)
			(size 0.254 0.8128)
			(layers "F.Cu" "F.Mask" "F.Paste")
			(net "P12V_NIC2_CO_ISET")
		)
		(pad "6" smd rect
			(at -1.400048 0.499872 180)
			(size 0.254 0.8128)
			(layers "F.Cu" "F.Mask" "F.Paste")
			(net "P12V_NIC2_CO_SS")
		)
		(pad "7" smd rect
			(at -1.400048 0.999998 180)
			(size 0.254 0.8128)
			(layers "F.Cu" "F.Mask" "F.Paste")
			(net "GND")
		)
		(pad "8" smd rect
			(at -1.400048 1.500124 180)
			(size 0.254 0.8128)
			(layers "F.Cu" "F.Mask" "F.Paste")
			(net "P12V_NIC2_CO_IMON_VR")
		)
		(pad "9" smd rect
			(at -1.400048 1.999996 180)
			(size 0.254 0.8128)
			(layers "F.Cu" "F.Mask" "F.Paste")
			(net "P12V_NIC2_CO_FLTB")
		)
		(pad "10" smd rect
			(at -0.499872 2.400046 270)
			(size 0.254 0.8128)
			(layers "F.Cu" "F.Mask" "F.Paste")
			(net "PWRGD_P12V_NIC2_CO")
		)
		(pad "11" smd rect
			(at 0.499872 2.400046 270)
			(size 0.254 0.8128)
			(layers "F.Cu" "F.Mask" "F.Paste")
			(net "P12V_NIC2_CO_OV_FB")
		)
		(pad "12" smd rect
			(at 1.400048 1.999996 180)
			(size 0.254 0.8128)
			(layers "F.Cu" "F.Mask" "F.Paste")
			(net "P12V_NIC2_CO_AVIN_PD")
		)
		(pad "13" smd rect
			(at 1.400048 1.500124 180)
			(size 0.254 0.8128)
			(layers "F.Cu" "F.Mask" "F.Paste")
			(net "P12V_NIC2_R")
		)
		(pad "14" smd rect
			(at 1.400048 0.999998 180)
			(size 0.254 0.8128)
			(layers "F.Cu" "F.Mask" "F.Paste")
			(net "P12V_NIC2_R")
		)
		(pad "15" smd rect
			(at 1.400048 0.499872 180)
			(size 0.254 0.8128)
			(layers "F.Cu" "F.Mask" "F.Paste")
			(net "P12V_NIC2_R")
		)
		(pad "16" smd rect
			(at 1.400048 0 180)
			(size 0.254 0.8128)
			(layers "F.Cu" "F.Mask" "F.Paste")
			(net "P12V_NIC2_R")
		)
		(pad "17" smd rect
			(at 1.400048 -0.499872 180)
			(size 0.254 0.8128)
			(layers "F.Cu" "F.Mask" "F.Paste")
			(net "P12V_NIC2_R")
		)
		(pad "18" smd rect
			(at 1.400048 -0.999998 180)
			(size 0.254 0.8128)
			(layers "F.Cu" "F.Mask" "F.Paste")
			(net "P12V_NIC2_R")
		)
		(pad "19" smd rect
			(at 1.400048 -1.500124 180)
			(size 0.254 0.8128)
			(layers "F.Cu" "F.Mask" "F.Paste")
			(net "P12V_NIC2_R")
		)
		(pad "20" smd rect
			(at 1.400048 -1.999996 180)
			(size 0.254 0.8128)
			(layers "F.Cu" "F.Mask" "F.Paste")
			(net "P12V_NIC2_R")
		)
		(pad "21_22" smd circle
			(at 0.499872 -2.337562 180)
			(size 0 0)
			(layers "F.Cu" "F.Mask" "F.Paste")
			(net "P12V_AUX")
		)
		(pad "23" smd rect
			(at 0 -1.100074 180)
			(size 0.254 1.27)
			(layers "F.Cu" "F.Mask" "F.Paste")
			(net "P12V_AUX")
		)
		(pad "24" smd rect
			(at 0 -0.199898 180)
			(size 0.254 1.27)
			(layers "F.Cu" "F.Mask" "F.Paste")
			(net "P12V_AUX")
		)
		(pad "25" smd rect
			(at 0 0.700024 180)
			(size 0.254 1.27)
			(layers "F.Cu" "F.Mask" "F.Paste")
			(net "P12V_AUX")
		)
		(pad "26" smd rect
			(at 0 1.599946 180)
			(size 0.254 1.27)
			(layers "F.Cu" "F.Mask" "F.Paste")
			(net "P12V_AUX")
		)
	)
)
